FILE_TYPE = MACRO_DRAWING;
SET COLOR_WIRE YELLOW;
SET COLOR_PROP ORANGE;
SET COLOR_DOT WHITE;
SET COLOR_ARC YELLOW;
SET COLOR_BODY GREEN;
SET COLOR_NOTE PURPLE;
SET PROP_DISPLAY VALUE;
SET PAGE_NUMBER P121;
FORCEADD QUANTA_TITLE_BLOCK_C..1
(-550 100);
FORCEPROP 1 LAST CUSTOM_TXT_CDS <NAME_2>
J 0
(-3725 150);
FORCEPROP 1 LAST CUSTOM_TXT_CDS <NAME_1>
J 0
(-3725 275);
FORCEPROP 1 LAST CUSTOM_TXT_CDS <Q_NUMBER>
J 0
(-1953 203);
DISPLAY 1.212766 (-1953 203);
FORCEPROP 1 LAST CUSTOM_TXT_CDS <Q_PROJ>
J 0
(-2932 202);
DISPLAY 1.212766 (-2932 202);
FORCEPROP 1 LAST CUSTOM_TXT_CDS <Q_REV>
J 0
(-734 203);
DISPLAY 1.212766 (-734 203);
FORCEPROP 1 LAST CUSTOM_TXT_CDS <CON_LAST_MODIFIED>
J 0
(-2435 115);
DISPLAY 0.978723 (-2435 115);
FORCEPROP 1 LAST CUSTOM_TXT_CDS <CON_PAGE_NUM> OF <CON_TOTAL_PAGES>
J 0
(-996 118);
DISPLAY 0.978723 (-996 118);
FORCEPROP 1 LAST Q_TITLE OCP 3.0 - PWR EN & RESET
J 0
(-9825 175);
DISPLAY 2.446809 (-9825 175);
PAINT GREEN (-9825 175);
FORCEPROP 1 LAST Q_DEPT BU9
J 1
(-4313 149);
DISPLAY 1.957447 (-4313 149);
PAINT GREEN (-4313 149);
FORCEPROP 0 LAST CDS_CON_LAST_MODIFIED Wed Jul 21 11:36:19 2021
J 0
(-2435 115);
DISPLAY INVISIBLE (-2435 115);
FORCEPROP 2 LAST CDS_LIB pure_quanta
J 0
(-550 100);
DISPLAY INVISIBLE (-550 100);
FORCEPROP 1 LAST CDS_LMAN_SYM_OUTLINE -9475,6775,100,-125
J 0
(-550 100);
DISPLAY 0.468085 (-550 100);
PAINT GREEN (-550 100);
DISPLAY INVISIBLE (-550 100);
FORCEPROP 2 LAST PAGE_BORDER TRUE
J 0
(-8440 5350);
DISPLAY 0.638298 (-8440 5350);
PAINT PINK (-8440 5350);
DISPLAY INVISIBLE (-8440 5350);
FORCEPROP 1 LAST COMMENT_BODY TRUE
J 0
(-538 87);
DISPLAY 0.978723 (-538 87);
PAINT GREEN (-538 87);
DISPLAY INVISIBLE (-538 87);
FORCEPROP 2 LAST CUSTOM_TXT_CDS <XR_PAGE_TITLE>
J 0
(-8440 5350);
DISPLAY 0.638298 (-8440 5350);
PAINT PINK (-8440 5350);
DISPLAY INVISIBLE (-8440 5350);
FORCEPROP 2 LAST CDS_XR_PAGE_TITLE CR-121 : @T6G_MB_LIB.T6G(SCH_1):PAGE121
J 0
(-8440 5350);
DISPLAY 0.638298 (-8440 5350);
PAINT PINK (-8440 5350);
DISPLAY INVISIBLE (-8440 5350);
QUIT
